(kicad_pcb
	(version 20241229)
	(generator "pcbnew")
	(generator_version "9.0")
	(general
		(thickness 1.599998)
		(legacy_teardrops no)
	)
	(paper "A4")
	(title_block
		(date "2023-02-12")
		(rev "1.1.5")
		(comment 9 "footprints 56-61 of 473")
	)
	(layers
		(0 "F.Cu" signal)
		(4 "In1.Cu" power "In1.GND")
		(6 "In2.Cu" signal)
		(8 "In3.Cu" power "In3.GND")
		(10 "In4.Cu" power "In4.VCC")
		(12 "In5.Cu" signal)
		(14 "In6.Cu" power "In6.VCC")
		(2 "B.Cu" signal)
		(9 "F.Adhes" user "F.Adhesive")
		(11 "B.Adhes" user "B.Adhesive")
		(13 "F.Paste" user)
		(15 "B.Paste" user)
		(5 "F.SilkS" user "F.Silkscreen")
		(7 "B.SilkS" user "B.Silkscreen")
		(1 "F.Mask" user)
		(3 "B.Mask" user)
		(17 "Dwgs.User" user "User.Drawings")
		(19 "Cmts.User" user "User.Comments")
		(21 "Eco1.User" user "User.Eco1")
		(23 "Eco2.User" user "User.Eco2")
		(25 "Edge.Cuts" user)
		(27 "Margin" user)
		(31 "F.CrtYd" user "F.Courtyard")
		(29 "B.CrtYd" user "B.Courtyard")
		(35 "F.Fab" user)
		(33 "B.Fab" user)
	)
	(footprint "antmicro-footprints:SC70-3"
		(layer "F.Cu")
		(at 199.686328 87.05)
		(property "Reference" "Q7"
			(at -0.79 2.05 0)
			(layer "F.SilkS")
			(effects
				(font
					(size 0.7 0.7)
					(thickness 0.15)
				)
				(justify left bottom)
			)
		)
		(property "Value" "BSS138PW"
			(at 0 2.3 0)
			(layer "F.Fab")
			(effects
				(font
					(size 0.7 0.7)
					(thickness 0.15)
				)
				(justify left bottom)
			)
		)
		(property "Description" "60 V, 320 mA N-channel enhancement mode Trench MOSFET, SC-70-3 aka SOT-323 package"
			(at 0 0 0)
			(layer "F.Fab")
			(hide yes)
			(effects
				(font
					(size 1.27 1.27)
					(thickness 0.15)
				)
			)
		)
		(property "Author" "Antmicro"
			(at 0 0 0)
			(layer "F.Fab")
			(hide yes)
			(effects
				(font
					(size 1 1)
					(thickness 0.15)
				)
			)
		)
		(property "License" "Apache-2.0"
			(at 0 0 0)
			(layer "F.Fab")
			(hide yes)
			(effects
				(font
					(size 1 1)
					(thickness 0.15)
				)
			)
		)
		(property "MPN" "BSS138PW"
			(at 0 0 0)
			(layer "F.Fab")
			(hide yes)
			(effects
				(font
					(size 1 1)
					(thickness 0.15)
				)
			)
		)
		(property "Manufacturer" "Nexperia"
			(at 0 0 0)
			(layer "F.Fab")
			(hide yes)
			(effects
				(font
					(size 1 1)
					(thickness 0.15)
				)
			)
		)
		(sheetname "Config SPI flash")
		(sheetfile "config-spi.kicad_sch")
		(attr smd)
		(fp_line
			(start -0.3 -1)
			(end 0.627 -0.999)
			(stroke
				(width 0.15)
				(type solid)
			)
			(layer "F.SilkS")
		)
		(fp_line
			(start -0.3 1)
			(end 0.627 1.001)
			(stroke
				(width 0.15)
				(type solid)
			)
			(layer "F.SilkS")
		)
		(fp_line
			(start 0.627 -0.6)
			(end 0.627 -0.999)
			(stroke
				(width 0.15)
				(type solid)
			)
			(layer "F.SilkS")
		)
		(fp_line
			(start 0.627 0.6)
			(end 0.627 1.001)
			(stroke
				(width 0.15)
				(type solid)
			)
			(layer "F.SilkS")
		)
		(fp_line
			(start -1.4 1)
			(end -1.4 -1)
			(stroke
				(width 0.05)
				(type solid)
			)
			(layer "F.CrtYd")
		)
		(fp_line
			(start -0.9 -1.3)
			(end -0.9 -1)
			(stroke
				(width 0.05)
				(type solid)
			)
			(layer "F.CrtYd")
		)
		(fp_line
			(start -0.9 -1.3)
			(end 0.9 -1.3)
			(stroke
				(width 0.05)
				(type solid)
			)
			(layer "F.CrtYd")
		)
		(fp_line
			(start -0.9 -1)
			(end -1.4 -1)
			(stroke
				(width 0.05)
				(type solid)
			)
			(layer "F.CrtYd")
		)
		(fp_line
			(start -0.9 1)
			(end -1.4 1)
			(stroke
				(width 0.05)
				(type solid)
			)
			(layer "F.CrtYd")
		)
		(fp_line
			(start -0.9 1.3)
			(end -0.9 1)
			(stroke
				(width 0.05)
				(type solid)
			)
			(layer "F.CrtYd")
		)
		(fp_line
			(start 0.9 -1.3)
			(end 0.9 -0.4)
			(stroke
				(width 0.05)
				(type solid)
			)
			(layer "F.CrtYd")
		)
		(fp_line
			(start 0.9 -0.4)
			(end 1.4 -0.4)
			(stroke
				(width 0.05)
				(type solid)
			)
			(layer "F.CrtYd")
		)
		(fp_line
			(start 0.9 0.4)
			(end 0.9 1.3)
			(stroke
				(width 0.05)
				(type solid)
			)
			(layer "F.CrtYd")
		)
		(fp_line
			(start 0.9 1.3)
			(end -0.9 1.3)
			(stroke
				(width 0.05)
				(type solid)
			)
			(layer "F.CrtYd")
		)
		(fp_line
			(start 1.4 -0.4)
			(end 1.4 0.4)
			(stroke
				(width 0.05)
				(type solid)
			)
			(layer "F.CrtYd")
		)
		(fp_line
			(start 1.4 0.4)
			(end 0.9 0.4)
			(stroke
				(width 0.05)
				(type solid)
			)
			(layer "F.CrtYd")
		)
		(fp_rect
			(start -0.623 -0.999)
			(end 0.627 1.001)
			(stroke
				(width 0.15)
				(type solid)
			)
			(fill no)
			(layer "F.Fab")
		)
		(pad "1" smd rect
			(at -0.95 -0.65 90)
			(size 0.6 0.8)
			(layers "F.Cu" "F.Mask" "F.Paste")
			(net 210 "INIT_B")
			(pinfunction "G")
			(pintype "bidirectional")
		)
		(pad "2" smd rect
			(at -0.95 0.65 90)
			(size 0.6 0.8)
			(layers "F.Cu" "F.Mask" "F.Paste")
			(net 5 "GND")
			(pinfunction "S")
			(pintype "bidirectional")
		)
		(pad "3" smd rect
			(at 0.95 0 90)
			(size 0.6 0.8)
			(layers "F.Cu" "F.Mask" "F.Paste")
			(net 233 "Net-(Q7-D)")
			(pinfunction "D")
			(pintype "bidirectional")
		)
	)
	(footprint "antmicro-footprints:R_0402_1005Metric"
		(layer "F.Cu")
		(at 173.375 111.667 90)
		(descr "Resistor SMD 0402")
		(tags "resistor SMD 0402")
		(property "Reference" "R60"
			(at 0.767 0.425 90)
			(layer "F.SilkS")
			(effects
				(font
					(size 0.7 0.7)
					(thickness 0.15)
				)
				(justify left bottom)
			)
		)
		(property "Value" "R_100R_0402"
			(at 0 1.4 90)
			(layer "F.Fab")
			(effects
				(font
					(size 0.7 0.7)
					(thickness 0.15)
				)
				(justify left bottom)
			)
		)
		(property "Description" "100R resistor in 0402 package with 1% tolerance"
			(at 0 0 90)
			(layer "F.Fab")
			(hide yes)
			(effects
				(font
					(size 1.27 1.27)
					(thickness 0.15)
				)
			)
		)
		(property "Author" "Antmicro"
			(at 285.042 -61.708 0)
			(layer "F.Fab")
			(hide yes)
			(effects
				(font
					(size 1 1)
					(thickness 0.15)
				)
			)
		)
		(property "License" "Apache-2.0"
			(at 285.042 -61.708 0)
			(layer "F.Fab")
			(hide yes)
			(effects
				(font
					(size 1 1)
					(thickness 0.15)
				)
			)
		)
		(property "MPN" "CR0402-FX-1000GLF"
			(at 285.042 -61.708 0)
			(layer "F.Fab")
			(hide yes)
			(effects
				(font
					(size 1 1)
					(thickness 0.15)
				)
			)
		)
		(property "Manufacturer" "Bourns"
			(at 285.042 -61.708 0)
			(layer "F.Fab")
			(hide yes)
			(effects
				(font
					(size 1 1)
					(thickness 0.15)
				)
			)
		)
		(property "Tolerance" "1%"
			(at 285.042 -61.708 0)
			(layer "F.Fab")
			(hide yes)
			(effects
				(font
					(size 1 1)
					(thickness 0.15)
				)
			)
		)
		(property "Val" "100R"
			(at 285.042 -61.708 0)
			(layer "F.Fab")
			(hide yes)
			(effects
				(font
					(size 1 1)
					(thickness 0.15)
				)
			)
		)
		(sheetname "Config SPI flash")
		(sheetfile "config-spi.kicad_sch")
		(attr smd)
		(fp_rect
			(start -0.93 -0.47)
			(end 0.93 0.47)
			(stroke
				(width 0.05)
				(type solid)
			)
			(fill no)
			(layer "F.CrtYd")
		)
		(fp_rect
			(start -0.5 -0.25)
			(end 0.5 0.25)
			(stroke
				(width 0.15)
				(type solid)
			)
			(fill no)
			(layer "F.Fab")
		)
		(pad "1" smd roundrect
			(at -0.485 0 90)
			(size 0.59 0.64)
			(layers "F.Cu" "F.Mask" "F.Paste")
			(roundrect_rratio 0.25)
			(net 459 "3V3_SYS")
			(pintype "passive")
		)
		(pad "2" smd roundrect
			(at 0.485 0 90)
			(size 0.59 0.64)
			(layers "F.Cu" "F.Mask" "F.Paste")
			(roundrect_rratio 0.25)
			(net 95 "PUDC_B")
			(pintype "passive")
		)
	)
	(footprint "antmicro-footprints:R_0402_1005Metric"
		(layer "F.Cu")
		(at 204.186328 79.320008 -90)
		(descr "Resistor SMD 0402")
		(tags "resistor SMD 0402")
		(property "Reference" "R64"
			(at 3.079992 -0.413672 270)
			(layer "F.SilkS")
			(effects
				(font
					(size 0.7 0.7)
					(thickness 0.15)
				)
				(justify left bottom)
			)
		)
		(property "Value" "R_0R_0402"
			(at 0 1.4 270)
			(layer "F.Fab")
			(effects
				(font
					(size 0.7 0.7)
					(thickness 0.15)
				)
				(justify left bottom)
			)
		)
		(property "Description" "0R resistor in 0402 package with unspecified tolerance"
			(at 0 0 270)
			(layer "F.Fab")
			(hide yes)
			(effects
				(font
					(size 1.27 1.27)
					(thickness 0.15)
				)
			)
		)
		(property "Author" "Antmicro"
			(at 124.86632 283.506336 0)
			(layer "F.Fab")
			(hide yes)
			(effects
				(font
					(size 1 1)
					(thickness 0.15)
				)
			)
		)
		(property "Current" "1A"
			(at 124.86632 283.506336 0)
			(layer "F.Fab")
			(hide yes)
			(effects
				(font
					(size 1 1)
					(thickness 0.15)
				)
			)
		)
		(property "License" "Apache-2.0"
			(at 124.86632 283.506336 0)
			(layer "F.Fab")
			(hide yes)
			(effects
				(font
					(size 1 1)
					(thickness 0.15)
				)
			)
		)
		(property "MPN" "ERJ2GE0R00X"
			(at 124.86632 283.506336 0)
			(layer "F.Fab")
			(hide yes)
			(effects
				(font
					(size 1 1)
					(thickness 0.15)
				)
			)
		)
		(property "Manufacturer" "Panasonic"
			(at 124.86632 283.506336 0)
			(layer "F.Fab")
			(hide yes)
			(effects
				(font
					(size 1 1)
					(thickness 0.15)
				)
			)
		)
		(property "Tolerance" ""
			(at 124.86632 283.506336 0)
			(layer "F.Fab")
			(hide yes)
			(effects
				(font
					(size 1 1)
					(thickness 0.15)
				)
			)
		)
		(property "Val" "0R"
			(at 124.86632 283.506336 0)
			(layer "F.Fab")
			(hide yes)
			(effects
				(font
					(size 1 1)
					(thickness 0.15)
				)
			)
		)
		(sheetname "Config SPI flash")
		(sheetfile "config-spi.kicad_sch")
		(attr exclude_from_pos_files exclude_from_bom dnp)
		(fp_rect
			(start -0.93 -0.47)
			(end 0.93 0.47)
			(stroke
				(width 0.05)
				(type solid)
			)
			(fill no)
			(layer "F.CrtYd")
		)
		(fp_rect
			(start -0.5 -0.25)
			(end 0.5 0.25)
			(stroke
				(width 0.15)
				(type solid)
			)
			(fill no)
			(layer "F.Fab")
		)
		(pad "1" smd roundrect
			(at -0.485 0 270)
			(size 0.59 0.64)
			(layers "F.Cu" "F.Mask" "F.Paste")
			(roundrect_rratio 0.25)
			(net 20 "MODE1")
			(pintype "passive")
		)
		(pad "2" smd roundrect
			(at 0.485 0 270)
			(size 0.59 0.64)
			(layers "F.Cu" "F.Mask" "F.Paste")
			(roundrect_rratio 0.25)
			(net 459 "3V3_SYS")
			(pintype "passive")
		)
	)
	(footprint "antmicro-footprints:R_0402_1005Metric"
		(layer "F.Cu")
		(at 203.086328 79.320008 -90)
		(descr "Resistor SMD 0402")
		(tags "resistor SMD 0402")
		(property "Reference" "R65"
			(at 3.079992 -0.413672 270)
			(layer "F.SilkS")
			(effects
				(font
					(size 0.7 0.7)
					(thickness 0.15)
				)
				(justify left bottom)
			)
		)
		(property "Value" "R_0R_0402"
			(at 0 1.4 270)
			(layer "F.Fab")
			(effects
				(font
					(size 0.7 0.7)
					(thickness 0.15)
				)
				(justify left bottom)
			)
		)
		(property "Description" "0R resistor in 0402 package with unspecified tolerance"
			(at 0 0 270)
			(layer "F.Fab")
			(hide yes)
			(effects
				(font
					(size 1.27 1.27)
					(thickness 0.15)
				)
			)
		)
		(property "Author" "Antmicro"
			(at 123.76632 282.406336 0)
			(layer "F.Fab")
			(hide yes)
			(effects
				(font
					(size 1 1)
					(thickness 0.15)
				)
			)
		)
		(property "Current" "1A"
			(at 123.76632 282.406336 0)
			(layer "F.Fab")
			(hide yes)
			(effects
				(font
					(size 1 1)
					(thickness 0.15)
				)
			)
		)
		(property "License" "Apache-2.0"
			(at 123.76632 282.406336 0)
			(layer "F.Fab")
			(hide yes)
			(effects
				(font
					(size 1 1)
					(thickness 0.15)
				)
			)
		)
		(property "MPN" "ERJ2GE0R00X"
			(at 123.76632 282.406336 0)
			(layer "F.Fab")
			(hide yes)
			(effects
				(font
					(size 1 1)
					(thickness 0.15)
				)
			)
		)
		(property "Manufacturer" "Panasonic"
			(at 123.76632 282.406336 0)
			(layer "F.Fab")
			(hide yes)
			(effects
				(font
					(size 1 1)
					(thickness 0.15)
				)
			)
		)
		(property "Tolerance" ""
			(at 123.76632 282.406336 0)
			(layer "F.Fab")
			(hide yes)
			(effects
				(font
					(size 1 1)
					(thickness 0.15)
				)
			)
		)
		(property "Val" "0R"
			(at 123.76632 282.406336 0)
			(layer "F.Fab")
			(hide yes)
			(effects
				(font
					(size 1 1)
					(thickness 0.15)
				)
			)
		)
		(sheetname "Config SPI flash")
		(sheetfile "config-spi.kicad_sch")
		(attr smd)
		(fp_rect
			(start -0.93 -0.47)
			(end 0.93 0.47)
			(stroke
				(width 0.05)
				(type solid)
			)
			(fill no)
			(layer "F.CrtYd")
		)
		(fp_rect
			(start -0.5 -0.25)
			(end 0.5 0.25)
			(stroke
				(width 0.15)
				(type solid)
			)
			(fill no)
			(layer "F.Fab")
		)
		(pad "1" smd roundrect
			(at -0.485 0 270)
			(size 0.59 0.64)
			(layers "F.Cu" "F.Mask" "F.Paste")
			(roundrect_rratio 0.25)
			(net 20 "MODE1")
			(pintype "passive")
		)
		(pad "2" smd roundrect
			(at 0.485 0 270)
			(size 0.59 0.64)
			(layers "F.Cu" "F.Mask" "F.Paste")
			(roundrect_rratio 0.25)
			(net 5 "GND")
			(pintype "passive")
		)
	)
	(footprint "antmicro-footprints:R_0402_1005Metric"
		(layer "F.Cu")
		(at 168.822 115.731 180)
		(descr "Resistor SMD 0402")
		(tags "resistor SMD 0402")
		(property "Reference" "R47"
			(at 1.322 -3.969 180)
			(layer "F.SilkS")
			(effects
				(font
					(size 0.7 0.7)
					(thickness 0.15)
				)
				(justify left bottom)
			)
		)
		(property "Value" "R_0R_0402"
			(at 0 1.4 180)
			(layer "F.Fab")
			(effects
				(font
					(size 0.7 0.7)
					(thickness 0.15)
				)
				(justify left bottom)
			)
		)
		(property "Description" "0R resistor in 0402 package with unspecified tolerance"
			(at 0 0 180)
			(layer "F.Fab")
			(hide yes)
			(effects
				(font
					(size 1.27 1.27)
					(thickness 0.15)
				)
			)
		)
		(property "Author" "Antmicro"
			(at 337.644 231.462 0)
			(layer "F.Fab")
			(hide yes)
			(effects
				(font
					(size 1 1)
					(thickness 0.15)
				)
			)
		)
		(property "Current" "1A"
			(at 337.644 231.462 0)
			(layer "F.Fab")
			(hide yes)
			(effects
				(font
					(size 1 1)
					(thickness 0.15)
				)
			)
		)
		(property "License" "Apache-2.0"
			(at 337.644 231.462 0)
			(layer "F.Fab")
			(hide yes)
			(effects
				(font
					(size 1 1)
					(thickness 0.15)
				)
			)
		)
		(property "MPN" "ERJ2GE0R00X"
			(at 337.644 231.462 0)
			(layer "F.Fab")
			(hide yes)
			(effects
				(font
					(size 1 1)
					(thickness 0.15)
				)
			)
		)
		(property "Manufacturer" "Panasonic"
			(at 337.644 231.462 0)
			(layer "F.Fab")
			(hide yes)
			(effects
				(font
					(size 1 1)
					(thickness 0.15)
				)
			)
		)
		(property "Tolerance" ""
			(at 337.644 231.462 0)
			(layer "F.Fab")
			(hide yes)
			(effects
				(font
					(size 1 1)
					(thickness 0.15)
				)
			)
		)
		(property "Val" "0R"
			(at 337.644 231.462 0)
			(layer "F.Fab")
			(hide yes)
			(effects
				(font
					(size 1 1)
					(thickness 0.15)
				)
			)
		)
		(sheetname "Config SPI flash")
		(sheetfile "config-spi.kicad_sch")
		(attr smd)
		(fp_rect
			(start -0.93 -0.47)
			(end 0.93 0.47)
			(stroke
				(width 0.05)
				(type solid)
			)
			(fill no)
			(layer "F.CrtYd")
		)
		(fp_rect
			(start -0.5 -0.25)
			(end 0.5 0.25)
			(stroke
				(width 0.15)
				(type solid)
			)
			(fill no)
			(layer "F.Fab")
		)
		(pad "1" smd roundrect
			(at -0.485 0 180)
			(size 0.59 0.64)
			(layers "F.Cu" "F.Mask" "F.Paste")
			(roundrect_rratio 0.25)
			(net 255 "Net-(U5-*CS)")
			(pintype "passive")
		)
		(pad "2" smd roundrect
			(at 0.485 0 180)
			(size 0.59 0.64)
			(layers "F.Cu" "F.Mask" "F.Paste")
			(roundrect_rratio 0.25)
			(net 212 "FCS_B")
			(pintype "passive")
		)
	)
	(footprint "antmicro-footprints:R_0402_1005Metric"
		(layer "F.Cu")
		(at 168.822 118.271 180)
		(descr "Resistor SMD 0402")
		(tags "resistor SMD 0402")
		(property "Reference" "R50"
			(at 1.322 -3.529 180)
			(layer "F.SilkS")
			(effects
				(font
					(size 0.7 0.7)
					(thickness 0.15)
				)
				(justify left bottom)
			)
		)
		(property "Value" "R_0R_0402"
			(at 0 1.4 180)
			(layer "F.Fab")
			(effects
				(font
					(size 0.7 0.7)
					(thickness 0.15)
				)
				(justify left bottom)
			)
		)
		(property "Description" "0R resistor in 0402 package with unspecified tolerance"
			(at 0 0 180)
			(layer "F.Fab")
			(hide yes)
			(effects
				(font
					(size 1.27 1.27)
					(thickness 0.15)
				)
			)
		)
		(property "Author" "Antmicro"
			(at 337.644 236.542 0)
			(layer "F.Fab")
			(hide yes)
			(effects
				(font
					(size 1 1)
					(thickness 0.15)
				)
			)
		)
		(property "Current" "1A"
			(at 337.644 236.542 0)
			(layer "F.Fab")
			(hide yes)
			(effects
				(font
					(size 1 1)
					(thickness 0.15)
				)
			)
		)
		(property "License" "Apache-2.0"
			(at 337.644 236.542 0)
			(layer "F.Fab")
			(hide yes)
			(effects
				(font
					(size 1 1)
					(thickness 0.15)
				)
			)
		)
		(property "MPN" "ERJ2GE0R00X"
			(at 337.644 236.542 0)
			(layer "F.Fab")
			(hide yes)
			(effects
				(font
					(size 1 1)
					(thickness 0.15)
				)
			)
		)
		(property "Manufacturer" "Panasonic"
			(at 337.644 236.542 0)
			(layer "F.Fab")
			(hide yes)
			(effects
				(font
					(size 1 1)
					(thickness 0.15)
				)
			)
		)
		(property "Tolerance" ""
			(at 337.644 236.542 0)
			(layer "F.Fab")
			(hide yes)
			(effects
				(font
					(size 1 1)
					(thickness 0.15)
				)
			)
		)
		(property "Val" "0R"
			(at 337.644 236.542 0)
			(layer "F.Fab")
			(hide yes)
			(effects
				(font
					(size 1 1)
					(thickness 0.15)
				)
			)
		)
		(sheetname "Config SPI flash")
		(sheetfile "config-spi.kicad_sch")
		(attr smd)
		(fp_rect
			(start -0.93 -0.47)
			(end 0.93 0.47)
			(stroke
				(width 0.05)
				(type solid)
			)
			(fill no)
			(layer "F.CrtYd")
		)
		(fp_rect
			(start -0.5 -0.25)
			(end 0.5 0.25)
			(stroke
				(width 0.15)
				(type solid)
			)
			(fill no)
			(layer "F.Fab")
		)
		(pad "1" smd roundrect
			(at -0.485 0 180)
			(size 0.59 0.64)
			(layers "F.Cu" "F.Mask" "F.Paste")
			(roundrect_rratio 0.25)
			(net 258 "Net-(U5-*WP{slash}IO2)")
			(pintype "passive")
		)
		(pad "2" smd roundrect
			(at 0.485 0 180)
			(size 0.59 0.64)
			(layers "F.Cu" "F.Mask" "F.Paste")
			(roundrect_rratio 0.25)
			(net 17 "QSPI_DQ2")
			(pintype "passive")
		)
	)
)
